(kicad_pcb
	(version 20260206)
	(generator "pcbnew")
	(generator_version "10.0")
	(general
		(thickness 1.6)
		(legacy_teardrops no)
	)
	(paper "A4")
	(title_block
		(title "04192023_DAF0TMB3IC0_F0TG_MB_C_brd_V02_OCP.brd")
		(comment 1 "Grand Teton / footprint 2783 of 8354 (U26), pads 3892-4002 of 6102")
	)
	(layers
		(0 "F.Cu" signal "TOP")
		(4 "In1.Cu" signal "GND")
		(6 "In2.Cu" signal "IN1")
		(8 "In3.Cu" signal "GND1")
		(10 "In4.Cu" signal "IN2")
		(12 "In5.Cu" signal "GND2")
		(14 "In6.Cu" signal "IN3")
		(16 "In7.Cu" signal "GND3")
		(18 "In8.Cu" signal "VCC")
		(20 "In9.Cu" signal "VCC1")
		(22 "In10.Cu" signal "GND4")
		(24 "In11.Cu" signal "IN4")
		(26 "In12.Cu" signal "GND5")
		(28 "In13.Cu" signal "IN5")
		(30 "In14.Cu" signal "GND6")
		(32 "In15.Cu" signal "IN6")
		(34 "In16.Cu" signal "GND7")
		(2 "B.Cu" signal "BOTTOM")
		(9 "F.Adhes" user "F.Adhesive")
		(11 "B.Adhes" user "B.Adhesive")
		(13 "F.Paste" user "Package Geometry/Pastemask Top")
		(15 "B.Paste" user "Package Geometry/Pastemask Bottom")
		(5 "F.SilkS" user "Ref Des/Silkscreen Top")
		(7 "B.SilkS" user "Ref Des/Silkscreen Bottom")
		(1 "F.Mask" user "Board Geometry/Soldermask Top")
		(3 "B.Mask" user "Board Geometry/Soldermask Bottom")
		(17 "Dwgs.User" user "User.Drawings")
		(19 "Cmts.User" user "User.Comments")
		(21 "Eco1.User" user "User.Eco1")
		(23 "Eco2.User" user "User.Eco2")
		(25 "Edge.Cuts" user "Board Geometry/Outline")
		(27 "Margin" user)
		(31 "F.CrtYd" user "Package Geometry/Place Bound Top")
		(29 "B.CrtYd" user "Package Geometry/Place Bound Bottom")
		(35 "F.Fab" user "Ref Des/Assembly Top")
		(33 "B.Fab" user "Ref Des/Assembly Bottom")
	)
	(footprint ""
		(layer "F.Cu")
		(at 111.927894 -258.880356 180)
		(property "Reference" "U26"
			(at -45.05579 -61.794136 0)
			(unlocked yes)
			(layer "F.SilkS")
			(effects
				(font
					(size 0.7874 0.5842)
					(thickness 0.1524)
				)
			)
		)
		(property "Value" ""
			(at 0 0 180)
			(layer "F.Fab")
			(effects
				(font
					(size 1.27 1.27)
				)
			)
		)
		(duplicate_pad_numbers_are_jumpers no)
		(pad "CT5" smd circle
			(at -31.170118 26.28011 180)
			(size 0.450088 0.450088)
			(layers "F.Cu" "F.Mask" "F.Paste")
			(net "PVDD11_S3_P1")
		)
		(pad "CT6" smd circle
			(at -30.230064 26.28011 180)
			(size 0.450088 0.450088)
			(layers "F.Cu" "F.Mask" "F.Paste")
			(net "M_K_CPU1_SB_DQS_DP<2>")
		)
		(pad "CT7" smd circle
			(at -29.29001 26.28011 180)
			(size 0.450088 0.450088)
			(layers "F.Cu" "F.Mask" "F.Paste")
			(net "M_K_CPU1_SB_DQ<19>")
		)
		(pad "CT8" smd circle
			(at -28.349956 26.28011 180)
			(size 0.450088 0.450088)
			(layers "F.Cu" "F.Mask" "F.Paste")
			(net "GND")
		)
		(pad "CT9" smd circle
			(at -27.409902 26.28011 180)
			(size 0.450088 0.450088)
			(layers "F.Cu" "F.Mask" "F.Paste")
			(net "M_L_CPU1_SB_DQS_DP<2>")
		)
		(pad "CT10" smd circle
			(at -26.470102 26.28011 180)
			(size 0.450088 0.450088)
			(layers "F.Cu" "F.Mask" "F.Paste")
			(net "GND")
		)
		(pad "CT11" smd circle
			(at -25.530048 26.28011 180)
			(size 0.450088 0.450088)
			(layers "F.Cu" "F.Mask" "F.Paste")
			(net "M_L_CPU1_SB_DQ<19>")
		)
		(pad "CT12" smd circle
			(at -24.589994 26.28011 180)
			(size 0.450088 0.450088)
			(layers "F.Cu" "F.Mask" "F.Paste")
			(net "PVDD11_S3_P1")
		)
		(pad "CT13" smd circle
			(at -23.64994 26.28011 180)
			(size 0.450088 0.450088)
			(layers "F.Cu" "F.Mask" "F.Paste")
			(net "M_H_CPU1_SB_DQS_DP<2>")
		)
		(pad "CT14" smd circle
			(at -22.709886 26.28011 180)
			(size 0.450088 0.450088)
			(layers "F.Cu" "F.Mask" "F.Paste")
			(net "M_H_CPU1_SB_DQ<19>")
		)
		(pad "CT15" smd circle
			(at -21.770086 26.28011 180)
			(size 0.450088 0.450088)
			(layers "F.Cu" "F.Mask" "F.Paste")
			(net "GND")
		)
		(pad "CT16" smd circle
			(at -20.830032 26.28011 180)
			(size 0.450088 0.450088)
			(layers "F.Cu" "F.Mask" "F.Paste")
			(net "M_J_CPU1_SB_DQS_DP<2>")
		)
		(pad "CT17" smd circle
			(at -19.889978 26.28011 180)
			(size 0.450088 0.450088)
			(layers "F.Cu" "F.Mask" "F.Paste")
			(net "GND")
		)
		(pad "CT18" smd circle
			(at -18.949924 26.28011 180)
			(size 0.450088 0.450088)
			(layers "F.Cu" "F.Mask" "F.Paste")
			(net "M_J_CPU1_SB_DQ<19>")
		)
		(pad "CT19" smd circle
			(at -18.010124 26.28011 180)
			(size 0.450088 0.450088)
			(layers "F.Cu" "F.Mask" "F.Paste")
			(net "PVDD11_S3_P1")
		)
		(pad "CT20" smd circle
			(at -17.07007 26.28011 180)
			(size 0.450088 0.450088)
			(layers "F.Cu" "F.Mask" "F.Paste")
			(net "M_I_CPU1_SB_DQS_DP<2>")
		)
		(pad "CT21" smd circle
			(at -16.130016 26.28011 180)
			(size 0.450088 0.450088)
			(layers "F.Cu" "F.Mask" "F.Paste")
			(net "M_I_CPU1_SB_DQ<19>")
		)
		(pad "CT22" smd circle
			(at -15.189962 26.28011 180)
			(size 0.450088 0.450088)
			(layers "F.Cu" "F.Mask" "F.Paste")
			(net "PVDD11_S3_P1")
		)
		(pad "CT23" smd circle
			(at -14.249908 26.28011 180)
			(size 0.450088 0.450088)
			(layers "F.Cu" "F.Mask" "F.Paste")
			(net "GND")
		)
		(pad "CT24" smd circle
			(at -13.310108 26.28011 180)
			(size 0.450088 0.450088)
			(layers "F.Cu" "F.Mask" "F.Paste")
			(net "GND")
		)
		(pad "CT25" smd circle
			(at -12.370054 26.28011 180)
			(size 0.450088 0.450088)
			(layers "F.Cu" "F.Mask" "F.Paste")
			(net "GND")
		)
		(pad "CT26" smd circle
			(at -11.43 26.28011 180)
			(size 0.450088 0.450088)
			(layers "F.Cu" "F.Mask" "F.Paste")
			(net "GND")
		)
		(pad "CT27" smd circle
			(at -10.489946 26.28011 180)
			(size 0.450088 0.450088)
			(layers "F.Cu" "F.Mask" "F.Paste")
			(net "GND")
		)
		(pad "CT28" smd circle
			(at -9.549892 26.28011 180)
			(size 0.450088 0.450088)
			(layers "F.Cu" "F.Mask" "F.Paste")
			(net "GND")
		)
		(pad "CT29" smd circle
			(at -8.610092 26.28011 180)
			(size 0.450088 0.450088)
			(layers "F.Cu" "F.Mask" "F.Paste")
			(net "GND")
		)
		(pad "CT30" smd circle
			(at -7.670038 26.28011 180)
			(size 0.450088 0.450088)
			(layers "F.Cu" "F.Mask" "F.Paste")
			(net "GND")
		)
		(pad "CT31" smd circle
			(at -6.729984 26.28011 180)
			(size 0.450088 0.450088)
			(layers "F.Cu" "F.Mask" "F.Paste")
			(net "GND")
		)
		(pad "CT32" smd circle
			(at -5.78993 26.28011 180)
			(size 0.450088 0.450088)
			(layers "F.Cu" "F.Mask" "F.Paste")
			(net "GND")
		)
		(pad "CT33" smd circle
			(at -4.849876 26.28011 180)
			(size 0.450088 0.450088)
			(layers "F.Cu" "F.Mask" "F.Paste")
			(net "GND")
		)
		(pad "CT34" smd circle
			(at -3.910076 26.28011 180)
			(size 0.450088 0.450088)
			(layers "F.Cu" "F.Mask" "F.Paste")
			(net "GND")
		)
		(pad "CT35" smd circle
			(at -2.970022 26.28011 180)
			(size 0.450088 0.450088)
			(layers "F.Cu" "F.Mask" "F.Paste")
			(net "P5E_CPU1_P2_RX_DP<2>")
		)
		(pad "CT36" smd circle
			(at -2.029968 26.28011 180)
			(size 0.450088 0.450088)
			(layers "F.Cu" "F.Mask" "F.Paste")
			(net "P5E_CPU1_P2_RX_DN<2>")
		)
		(pad "CT37" smd circle
			(at -1.089914 26.28011 180)
			(size 0.450088 0.450088)
			(layers "F.Cu" "F.Mask" "F.Paste")
			(net "GND")
		)
		(pad "CT39" smd circle
			(at 0.78994 26.28011 180)
			(size 0.450088 0.450088)
			(layers "F.Cu" "F.Mask" "F.Paste")
			(net "GND")
		)
		(pad "CT40" smd circle
			(at 1.729994 26.28011 180)
			(size 0.450088 0.450088)
			(layers "F.Cu" "F.Mask" "F.Paste")
			(net "P5E_CPU1_P0_TX_DN<13>")
		)
		(pad "CT41" smd circle
			(at 2.670048 26.28011 180)
			(size 0.450088 0.450088)
			(layers "F.Cu" "F.Mask" "F.Paste")
			(net "P5E_CPU1_P0_TX_DP<13>")
		)
		(pad "CT42" smd circle
			(at 3.610102 26.28011 180)
			(size 0.450088 0.450088)
			(layers "F.Cu" "F.Mask" "F.Paste")
			(net "GND")
		)
		(pad "CT43" smd circle
			(at 4.549902 26.28011 180)
			(size 0.450088 0.450088)
			(layers "F.Cu" "F.Mask" "F.Paste")
			(net "GND")
		)
		(pad "CT44" smd circle
			(at 5.489956 26.28011 180)
			(size 0.450088 0.450088)
			(layers "F.Cu" "F.Mask" "F.Paste")
			(net "GND")
		)
		(pad "CT45" smd circle
			(at 6.43001 26.28011 180)
			(size 0.450088 0.450088)
			(layers "F.Cu" "F.Mask" "F.Paste")
			(net "GND")
		)
		(pad "CT46" smd circle
			(at 7.370064 26.28011 180)
			(size 0.450088 0.450088)
			(layers "F.Cu" "F.Mask" "F.Paste")
			(net "GND")
		)
		(pad "CT47" smd circle
			(at 8.310118 26.28011 180)
			(size 0.450088 0.450088)
			(layers "F.Cu" "F.Mask" "F.Paste")
			(net "GND")
		)
		(pad "CT48" smd circle
			(at 9.249918 26.28011 180)
			(size 0.450088 0.450088)
			(layers "F.Cu" "F.Mask" "F.Paste")
			(net "GND")
		)
		(pad "CT49" smd circle
			(at 10.189972 26.28011 180)
			(size 0.450088 0.450088)
			(layers "F.Cu" "F.Mask" "F.Paste")
			(net "GND")
		)
		(pad "CT50" smd circle
			(at 11.130026 26.28011 180)
			(size 0.450088 0.450088)
			(layers "F.Cu" "F.Mask" "F.Paste")
			(net "GND")
		)
		(pad "CT51" smd circle
			(at 12.07008 26.28011 180)
			(size 0.450088 0.450088)
			(layers "F.Cu" "F.Mask" "F.Paste")
			(net "GND")
		)
		(pad "CT52" smd circle
			(at 13.00988 26.28011 180)
			(size 0.450088 0.450088)
			(layers "F.Cu" "F.Mask" "F.Paste")
			(net "GND")
		)
		(pad "CT53" smd circle
			(at 13.949934 26.28011 180)
			(size 0.450088 0.450088)
			(layers "F.Cu" "F.Mask" "F.Paste")
			(net "GND")
		)
		(pad "CT54" smd circle
			(at 14.889988 26.28011 180)
			(size 0.450088 0.450088)
			(layers "F.Cu" "F.Mask" "F.Paste")
			(net "PVDDIO_P1")
		)
		(pad "CT55" smd circle
			(at 15.830042 26.28011 180)
			(size 0.450088 0.450088)
			(layers "F.Cu" "F.Mask" "F.Paste")
			(net "M_C_CPU1_SB_DQ<19>")
		)
		(pad "CT56" smd circle
			(at 16.770096 26.28011 180)
			(size 0.450088 0.450088)
			(layers "F.Cu" "F.Mask" "F.Paste")
			(net "M_C_CPU1_SB_DQS_DP<2>")
		)
		(pad "CT57" smd circle
			(at 17.709896 26.28011 180)
			(size 0.450088 0.450088)
			(layers "F.Cu" "F.Mask" "F.Paste")
			(net "PVDDIO_P1")
		)
		(pad "CT58" smd circle
			(at 18.64995 26.28011 180)
			(size 0.450088 0.450088)
			(layers "F.Cu" "F.Mask" "F.Paste")
			(net "M_D_CPU1_SB_DQ<19>")
		)
		(pad "CT59" smd circle
			(at 19.590004 26.28011 180)
			(size 0.450088 0.450088)
			(layers "F.Cu" "F.Mask" "F.Paste")
			(net "GND")
		)
		(pad "CT60" smd circle
			(at 20.530058 26.28011 180)
			(size 0.450088 0.450088)
			(layers "F.Cu" "F.Mask" "F.Paste")
			(net "M_D_CPU1_SB_DQS_DP<2>")
		)
		(pad "CT61" smd circle
			(at 21.470112 26.28011 180)
			(size 0.450088 0.450088)
			(layers "F.Cu" "F.Mask" "F.Paste")
			(net "GND")
		)
		(pad "CT62" smd circle
			(at 22.409912 26.28011 180)
			(size 0.450088 0.450088)
			(layers "F.Cu" "F.Mask" "F.Paste")
			(net "M_B_CPU1_SB_DQ<19>")
		)
		(pad "CT63" smd circle
			(at 23.349966 26.28011 180)
			(size 0.450088 0.450088)
			(layers "F.Cu" "F.Mask" "F.Paste")
			(net "M_B_CPU1_SB_DQS_DP<2>")
		)
		(pad "CT64" smd circle
			(at 24.29002 26.28011 180)
			(size 0.450088 0.450088)
			(layers "F.Cu" "F.Mask" "F.Paste")
			(net "PVDDIO_P1")
		)
		(pad "CT65" smd circle
			(at 25.230074 26.28011 180)
			(size 0.450088 0.450088)
			(layers "F.Cu" "F.Mask" "F.Paste")
			(net "M_F_CPU1_SB_DQ<19>")
		)
		(pad "CT66" smd circle
			(at 26.170128 26.28011 180)
			(size 0.450088 0.450088)
			(layers "F.Cu" "F.Mask" "F.Paste")
			(net "GND")
		)
		(pad "CT67" smd circle
			(at 27.109928 26.28011 180)
			(size 0.450088 0.450088)
			(layers "F.Cu" "F.Mask" "F.Paste")
			(net "M_F_CPU1_SB_DQS_DP<2>")
		)
		(pad "CT68" smd circle
			(at 28.049982 26.28011 180)
			(size 0.450088 0.450088)
			(layers "F.Cu" "F.Mask" "F.Paste")
			(net "GND")
		)
		(pad "CT69" smd circle
			(at 28.990036 26.28011 180)
			(size 0.450088 0.450088)
			(layers "F.Cu" "F.Mask" "F.Paste")
			(net "M_E_CPU1_SB_DQ<19>")
		)
		(pad "CT70" smd circle
			(at 29.93009 26.28011 180)
			(size 0.450088 0.450088)
			(layers "F.Cu" "F.Mask" "F.Paste")
			(net "M_E_CPU1_SB_DQS_DP<2>")
		)
		(pad "CT71" smd circle
			(at 30.86989 26.28011 180)
			(size 0.450088 0.450088)
			(layers "F.Cu" "F.Mask" "F.Paste")
			(net "PVDDIO_P1")
		)
		(pad "CT72" smd circle
			(at 31.809944 26.28011 180)
			(size 0.450088 0.450088)
			(layers "F.Cu" "F.Mask" "F.Paste")
			(net "M_A_CPU1_SB_DQ<19>")
		)
		(pad "CT73" smd circle
			(at 32.749998 26.28011 180)
			(size 0.450088 0.450088)
			(layers "F.Cu" "F.Mask" "F.Paste")
			(net "GND")
		)
		(pad "CT74" smd circle
			(at 33.690052 26.28011 180)
			(size 0.450088 0.450088)
			(layers "F.Cu" "F.Mask" "F.Paste")
			(net "M_A_CPU1_SB_DQS_DP<2>")
		)
		(pad "CU1" smd circle
			(at -34.459926 27.090116 180)
			(size 0.450088 0.450088)
			(layers "F.Cu" "F.Mask" "F.Paste")
			(net "GND")
		)
		(pad "CU2" smd circle
			(at -33.519872 27.090116 180)
			(size 0.450088 0.450088)
			(layers "F.Cu" "F.Mask" "F.Paste")
			(net "M_G_CPU1_SB_DQS_DN<2>")
		)
		(pad "CU3" smd circle
			(at -32.580072 27.090116 180)
			(size 0.450088 0.450088)
			(layers "F.Cu" "F.Mask" "F.Paste")
			(net "M_G_CPU1_SB_DQS_DN<7>")
		)
		(pad "CU4" smd circle
			(at -31.640018 27.090116 180)
			(size 0.450088 0.450088)
			(layers "F.Cu" "F.Mask" "F.Paste")
			(net "GND")
		)
		(pad "CU5" smd circle
			(at -30.699964 27.090116 180)
			(size 0.450088 0.450088)
			(layers "F.Cu" "F.Mask" "F.Paste")
			(net "M_K_CPU1_SB_DQS_DN<2>")
		)
		(pad "CU6" smd circle
			(at -29.75991 27.090116 180)
			(size 0.450088 0.450088)
			(layers "F.Cu" "F.Mask" "F.Paste")
			(net "GND")
		)
		(pad "CU7" smd circle
			(at -28.82011 27.090116 180)
			(size 0.450088 0.450088)
			(layers "F.Cu" "F.Mask" "F.Paste")
			(net "M_K_CPU1_SB_DQS_DN<7>")
		)
		(pad "CU8" smd circle
			(at -27.880056 27.090116 180)
			(size 0.450088 0.450088)
			(layers "F.Cu" "F.Mask" "F.Paste")
			(net "GND")
		)
		(pad "CU9" smd circle
			(at -26.940002 27.090116 180)
			(size 0.450088 0.450088)
			(layers "F.Cu" "F.Mask" "F.Paste")
			(net "M_L_CPU1_SB_DQS_DN<2>")
		)
		(pad "CU10" smd circle
			(at -25.999948 27.090116 180)
			(size 0.450088 0.450088)
			(layers "F.Cu" "F.Mask" "F.Paste")
			(net "M_L_CPU1_SB_DQS_DN<7>")
		)
		(pad "CU11" smd circle
			(at -25.059894 27.090116 180)
			(size 0.450088 0.450088)
			(layers "F.Cu" "F.Mask" "F.Paste")
			(net "GND")
		)
		(pad "CU12" smd circle
			(at -24.120094 27.090116 180)
			(size 0.450088 0.450088)
			(layers "F.Cu" "F.Mask" "F.Paste")
			(net "M_H_CPU1_SB_DQS_DN<2>")
		)
		(pad "CU13" smd circle
			(at -23.18004 27.090116 180)
			(size 0.450088 0.450088)
			(layers "F.Cu" "F.Mask" "F.Paste")
			(net "GND")
		)
		(pad "CU14" smd circle
			(at -22.239986 27.090116 180)
			(size 0.450088 0.450088)
			(layers "F.Cu" "F.Mask" "F.Paste")
			(net "M_H_CPU1_SB_DQS_DN<7>")
		)
		(pad "CU15" smd circle
			(at -21.299932 27.090116 180)
			(size 0.450088 0.450088)
			(layers "F.Cu" "F.Mask" "F.Paste")
			(net "GND")
		)
		(pad "CU16" smd circle
			(at -20.359878 27.090116 180)
			(size 0.450088 0.450088)
			(layers "F.Cu" "F.Mask" "F.Paste")
			(net "M_J_CPU1_SB_DQS_DN<2>")
		)
		(pad "CU17" smd circle
			(at -19.420078 27.090116 180)
			(size 0.450088 0.450088)
			(layers "F.Cu" "F.Mask" "F.Paste")
			(net "M_J_CPU1_SB_DQS_DN<7>")
		)
		(pad "CU18" smd circle
			(at -18.480024 27.090116 180)
			(size 0.450088 0.450088)
			(layers "F.Cu" "F.Mask" "F.Paste")
			(net "GND")
		)
		(pad "CU19" smd circle
			(at -17.53997 27.090116 180)
			(size 0.450088 0.450088)
			(layers "F.Cu" "F.Mask" "F.Paste")
			(net "M_I_CPU1_SB_DQS_DN<2>")
		)
		(pad "CU20" smd circle
			(at -16.599916 27.090116 180)
			(size 0.450088 0.450088)
			(layers "F.Cu" "F.Mask" "F.Paste")
			(net "GND")
		)
		(pad "CU21" smd circle
			(at -15.660116 27.090116 180)
			(size 0.450088 0.450088)
			(layers "F.Cu" "F.Mask" "F.Paste")
			(net "M_I_CPU1_SB_DQS_DN<7>")
		)
		(pad "CU22" smd circle
			(at -14.720062 27.090116 180)
			(size 0.450088 0.450088)
			(layers "F.Cu" "F.Mask" "F.Paste")
			(net "GND")
		)
		(pad "CU23" smd circle
			(at -13.780008 27.090116 180)
			(size 0.450088 0.450088)
			(layers "F.Cu" "F.Mask" "F.Paste")
			(net "P5E_CPU1_P3_RX_DP<15>")
		)
		(pad "CU24" smd circle
			(at -12.839954 27.090116 180)
			(size 0.450088 0.450088)
			(layers "F.Cu" "F.Mask" "F.Paste")
			(net "P5E_CPU1_P3_RX_DN<15>")
		)
		(pad "CU25" smd circle
			(at -11.8999 27.090116 180)
			(size 0.450088 0.450088)
			(layers "F.Cu" "F.Mask" "F.Paste")
			(net "GND")
		)
		(pad "CU26" smd circle
			(at -10.9601 27.090116 180)
			(size 0.450088 0.450088)
			(layers "F.Cu" "F.Mask" "F.Paste")
			(net "P5E_CPU1_P2_RX_DP<10>")
		)
		(pad "CU27" smd circle
			(at -10.020046 27.090116 180)
			(size 0.450088 0.450088)
			(layers "F.Cu" "F.Mask" "F.Paste")
			(net "P5E_CPU1_P2_RX_DN<10>")
		)
		(pad "CU28" smd circle
			(at -9.079992 27.090116 180)
			(size 0.450088 0.450088)
			(layers "F.Cu" "F.Mask" "F.Paste")
			(net "GND")
		)
		(pad "CU29" smd circle
			(at -8.139938 27.090116 180)
			(size 0.450088 0.450088)
			(layers "F.Cu" "F.Mask" "F.Paste")
			(net "P5E_CPU1_P2_RX_DP<7>")
		)
		(pad "CU30" smd circle
			(at -7.199884 27.090116 180)
			(size 0.450088 0.450088)
			(layers "F.Cu" "F.Mask" "F.Paste")
			(net "P5E_CPU1_P2_RX_DN<7>")
		)
		(pad "CU31" smd circle
			(at -6.260084 27.090116 180)
			(size 0.450088 0.450088)
			(layers "F.Cu" "F.Mask" "F.Paste")
			(net "GND")
		)
		(pad "CU32" smd circle
			(at -5.32003 27.090116 180)
			(size 0.450088 0.450088)
			(layers "F.Cu" "F.Mask" "F.Paste")
			(net "P5E_CPU1_P2_RX_DP<4>")
		)
		(pad "CU33" smd circle
			(at -4.379976 27.090116 180)
			(size 0.450088 0.450088)
			(layers "F.Cu" "F.Mask" "F.Paste")
			(net "P5E_CPU1_P2_RX_DN<4>")
		)
		(pad "CU34" smd circle
			(at -3.439922 27.090116 180)
			(size 0.450088 0.450088)
			(layers "F.Cu" "F.Mask" "F.Paste")
			(net "GND")
		)
		(pad "CU35" smd circle
			(at -2.500122 27.090116 180)
			(size 0.450088 0.450088)
			(layers "F.Cu" "F.Mask" "F.Paste")
			(net "PVDDCR_CPU1_P1")
		)
		(pad "CU36" smd circle
			(at -1.560068 27.090116 180)
			(size 0.450088 0.450088)
			(layers "F.Cu" "F.Mask" "F.Paste")
			(net "PVDDCR_CPU1_P1")
		)
		(pad "CU40" smd circle
			(at 1.260094 27.090116 180)
			(size 0.450088 0.450088)
			(layers "F.Cu" "F.Mask" "F.Paste")
			(net "PVDDCR_CPU1_P1")
		)
		(pad "CU41" smd circle
			(at 2.199894 27.090116 180)
			(size 0.450088 0.450088)
			(layers "F.Cu" "F.Mask" "F.Paste")
			(net "PVDDCR_CPU1_P1")
		)
		(pad "CU42" smd circle
			(at 3.139948 27.090116 180)
			(size 0.450088 0.450088)
			(layers "F.Cu" "F.Mask" "F.Paste")
			(net "GND")
		)
		(pad "CU43" smd circle
			(at 4.080002 27.090116 180)
			(size 0.450088 0.450088)
			(layers "F.Cu" "F.Mask" "F.Paste")
			(net "P5E_CPU1_P0_TX_DN<11>")
		)
		(pad "CU44" smd circle
			(at 5.020056 27.090116 180)
			(size 0.450088 0.450088)
			(layers "F.Cu" "F.Mask" "F.Paste")
			(net "P5E_CPU1_P0_TX_DP<11>")
		)
		(pad "CU45" smd circle
			(at 5.96011 27.090116 180)
			(size 0.450088 0.450088)
			(layers "F.Cu" "F.Mask" "F.Paste")
			(net "GND")
		)
	)
)
